(kicad_pcb
	(version 20260206)
	(generator "pcbnew")
	(generator_version "10.0")
	(general
		(thickness 1.6)
		(legacy_teardrops no)
	)
	(paper "A4")
	(title_block
		(title "timecard-production-celestica-r4006 — R4006-B0001-02_R01.brd")
		(comment 1 "Time Appliance Project (Time Card) / footprints 753-757 of 1113")
	)
	(layers
		(0 "F.Cu" signal "TOP")
		(4 "In1.Cu" signal "L02_GND1")
		(6 "In2.Cu" signal "L03_SIG1")
		(8 "In3.Cu" signal "L04_GND2")
		(10 "In4.Cu" signal "L05_VCC1")
		(12 "In5.Cu" signal "L06_VCC2")
		(14 "In6.Cu" signal "L07_GND3")
		(16 "In7.Cu" signal "L08_SIG2")
		(18 "In8.Cu" signal "L09_GND4")
		(2 "B.Cu" signal "BOTTOM")
		(9 "F.Adhes" user "F.Adhesive")
		(11 "B.Adhes" user "B.Adhesive")
		(13 "F.Paste" user "Package Geometry/Pastemask Top")
		(15 "B.Paste" user "Package Geometry/Pastemask Bottom")
		(5 "F.SilkS" user "Ref Des/Silkscreen Top")
		(7 "B.SilkS" user "Ref Des/Silkscreen Bottom")
		(1 "F.Mask" user "Board Geometry/Soldermask Top")
		(3 "B.Mask" user "Board Geometry/Soldermask Bottom")
		(17 "Dwgs.User" user "User.Drawings")
		(19 "Cmts.User" user "User.Comments")
		(21 "Eco1.User" user "User.Eco1")
		(23 "Eco2.User" user "User.Eco2")
		(25 "Edge.Cuts" user "Board Geometry/Outline")
		(27 "Margin" user)
		(31 "F.CrtYd" user "Package Geometry/Place Bound Top")
		(29 "B.CrtYd" user "Package Geometry/Place Bound Bottom")
		(35 "F.Fab" user "Ref Des/Assembly Top")
		(33 "B.Fab" user "Ref Des/Assembly Bottom")
	)
	(footprint ""
		(layer "B.Cu")
		(at 95.631 -86.741)
		(property "Reference" "R205"
			(at -0.254 -5.54863 0)
			(unlocked yes)
			(layer "B.SilkS")
			(effects
				(font
					(size 0.7874 0.5842)
					(thickness 0.1524)
				)
				(justify mirror)
			)
		)
		(property "Value" "VAL*"
			(at -0.02032 2.13233 0)
			(unlocked yes)
			(layer "B.Fab")
			(hide yes)
			(effects
				(font
					(size 0.7874 0.5842)
					(thickness 0.1524)
				)
				(justify mirror)
			)
		)
		(property "Tolerance" "TOL*"
			(at -0.044704 3.05435 0)
			(unlocked yes)
			(layer "Cmts.User")
			(hide yes)
			(effects
				(font
					(size 0.7874 0.5842)
					(thickness 0.1524)
				)
				(justify mirror)
			)
		)
		(property "User Part Number" "PARTNUM*"
			(at -0.02032 4.024884 0)
			(unlocked yes)
			(layer "Cmts.User")
			(hide yes)
			(effects
				(font
					(size 0.7874 0.5842)
					(thickness 0.1524)
				)
				(justify mirror)
			)
		)
		(property "Device Type" "RESISTOR-G155-133R0-01,33OHM,1%"
			(at -0.008382 1.210564 0)
			(unlocked yes)
			(layer "B.Fab")
			(hide yes)
			(effects
				(font
					(size 0.7874 0.5842)
					(thickness 0.1524)
				)
				(justify mirror)
			)
		)
		(duplicate_pad_numbers_are_jumpers no)
		(fp_line
			(start -1.143 -0.5588)
			(end 1.143 -0.5588)
			(stroke
				(width 0.1)
				(type default)
			)
			(layer "B.SilkS")
		)
		(fp_line
			(start -1.143 0.5588)
			(end -1.143 -0.5588)
			(stroke
				(width 0.1)
				(type default)
			)
			(layer "B.SilkS")
		)
		(fp_line
			(start 1.143 -0.5588)
			(end 1.143 0.5588)
			(stroke
				(width 0.1)
				(type default)
			)
			(layer "B.SilkS")
		)
		(fp_line
			(start 1.143 0.5588)
			(end -1.143 0.5588)
			(stroke
				(width 0.1)
				(type default)
			)
			(layer "B.SilkS")
		)
		(fp_rect
			(start -1.143 0.5588)
			(end 1.143 -0.5588)
			(stroke
				(width 0)
				(type default)
			)
			(fill no)
			(layer "B.CrtYd")
		)
		(fp_line
			(start -0.508 -0.3048)
			(end 0.508 -0.3048)
			(stroke
				(width 0.1)
				(type default)
			)
			(layer "B.Fab")
		)
		(fp_line
			(start -0.508 0.3048)
			(end -0.508 -0.3048)
			(stroke
				(width 0.1)
				(type default)
			)
			(layer "B.Fab")
		)
		(fp_line
			(start 0.508 -0.3048)
			(end 0.508 0.3048)
			(stroke
				(width 0.1)
				(type default)
			)
			(layer "B.Fab")
		)
		(fp_line
			(start 0.508 0.3048)
			(end -0.508 0.3048)
			(stroke
				(width 0.1)
				(type default)
			)
			(layer "B.Fab")
		)
		(pad "1" smd rect
			(at 0.5334 0 180)
			(size 0.7112 0.6096)
			(layers "B.Cu" "B.Mask" "B.Paste")
			(net "UNNAMED_127_MT25QL128ABA1ESES_3")
		)
		(pad "2" smd rect
			(at -0.5334 0 180)
			(size 0.7112 0.6096)
			(layers "B.Cu" "B.Mask" "B.Paste")
			(net "FLASH_DQ2")
		)
		(zone
			(layer "B.Cu")
			(hatch none 0.5)
			(connect_pads
				(clearance 0)
			)
			(min_thickness 0.25)
			(keepout
				(tracks allowed)
				(vias not_allowed)
				(pads allowed)
				(copperpour not_allowed)
				(footprints allowed)
			)
			(placement
				(enabled no)
				(sheetname "")
			)
			(fill
				(thermal_gap 0.5)
				(thermal_bridge_width 0.5)
				(island_removal_mode 0)
			)
			(polygon
				(pts
					(xy 95.5548 -86.4362) (xy 95.7072 -86.4362) (xy 95.7072 -87.0458) (xy 95.5548 -87.0458)
				)
			)
		)
	)
	(footprint ""
		(layer "B.Cu")
		(at 119.761 -23.241 180)
		(property "Reference" "R483"
			(at 0 -1.18237 0)
			(unlocked yes)
			(layer "B.SilkS")
			(effects
				(font
					(size 0.7874 0.5842)
					(thickness 0.1524)
				)
				(justify mirror)
			)
		)
		(property "Value" "VAL*"
			(at -0.02032 2.13233 180)
			(unlocked yes)
			(layer "B.Fab")
			(hide yes)
			(effects
				(font
					(size 0.7874 0.5842)
					(thickness 0.1524)
				)
				(justify mirror)
			)
		)
		(property "Tolerance" "TOL*"
			(at -0.044704 3.05435 180)
			(unlocked yes)
			(layer "Cmts.User")
			(hide yes)
			(effects
				(font
					(size 0.7874 0.5842)
					(thickness 0.1524)
				)
				(justify mirror)
			)
		)
		(property "User Part Number" "PARTNUM*"
			(at -0.02032 4.024884 180)
			(unlocked yes)
			(layer "Cmts.User")
			(hide yes)
			(effects
				(font
					(size 0.7874 0.5842)
					(thickness 0.1524)
				)
				(justify mirror)
			)
		)
		(property "Device Type" "RESISTOR-G155-11001-01,1KOHM,1%"
			(at -0.008382 1.210564 180)
			(unlocked yes)
			(layer "B.Fab")
			(hide yes)
			(effects
				(font
					(size 0.7874 0.5842)
					(thickness 0.1524)
				)
				(justify mirror)
			)
		)
		(duplicate_pad_numbers_are_jumpers no)
		(fp_line
			(start 1.143 0.5588)
			(end -1.143 0.5588)
			(stroke
				(width 0.1)
				(type default)
			)
			(layer "B.SilkS")
		)
		(fp_line
			(start 1.143 -0.5588)
			(end 1.143 0.5588)
			(stroke
				(width 0.1)
				(type default)
			)
			(layer "B.SilkS")
		)
		(fp_line
			(start -1.143 0.5588)
			(end -1.143 -0.5588)
			(stroke
				(width 0.1)
				(type default)
			)
			(layer "B.SilkS")
		)
		(fp_line
			(start -1.143 -0.5588)
			(end 1.143 -0.5588)
			(stroke
				(width 0.1)
				(type default)
			)
			(layer "B.SilkS")
		)
		(fp_poly
			(pts
				(xy 1.143 0.5588) (xy -1.143 0.5588) (xy -1.143 -0.5588) (xy 1.143 -0.5588)
			)
			(stroke
				(width 0)
				(type default)
			)
			(fill no)
			(layer "B.CrtYd")
		)
		(fp_line
			(start 0.508 0.3048)
			(end -0.508 0.3048)
			(stroke
				(width 0.1)
				(type default)
			)
			(layer "B.Fab")
		)
		(fp_line
			(start 0.508 -0.3048)
			(end 0.508 0.3048)
			(stroke
				(width 0.1)
				(type default)
			)
			(layer "B.Fab")
		)
		(fp_line
			(start -0.508 0.3048)
			(end -0.508 -0.3048)
			(stroke
				(width 0.1)
				(type default)
			)
			(layer "B.Fab")
		)
		(fp_line
			(start -0.508 -0.3048)
			(end 0.508 -0.3048)
			(stroke
				(width 0.1)
				(type default)
			)
			(layer "B.Fab")
		)
		(pad "1" smd rect
			(at 0.5334 0)
			(size 0.7112 0.6096)
			(layers "B.Cu" "B.Mask" "B.Paste")
			(net "SG")
		)
		(pad "2" smd rect
			(at -0.5334 0)
			(size 0.7112 0.6096)
			(layers "B.Cu" "B.Mask" "B.Paste")
			(net "MUX3_SEL")
		)
		(zone
			(layer "B.Cu")
			(hatch none 0.5)
			(connect_pads
				(clearance 0)
			)
			(min_thickness 0.25)
			(keepout
				(tracks allowed)
				(vias not_allowed)
				(pads allowed)
				(copperpour not_allowed)
				(footprints allowed)
			)
			(placement
				(enabled no)
				(sheetname "")
			)
			(fill
				(thermal_gap 0.5)
				(thermal_bridge_width 0.5)
				(island_removal_mode 0)
			)
			(polygon
				(pts
					(xy 119.6848 -23.5458) (xy 119.6848 -22.9362) (xy 119.8372 -22.9362) (xy 119.8372 -23.5458)
				)
			)
		)
		(zone
			(layer "B.Cu")
			(hatch none 0.5)
			(connect_pads
				(clearance 0)
			)
			(min_thickness 0.25)
			(keepout
				(tracks not_allowed)
				(vias allowed)
				(pads allowed)
				(copperpour not_allowed)
				(footprints allowed)
			)
			(placement
				(enabled no)
				(sheetname "")
			)
			(fill
				(thermal_gap 0.5)
				(thermal_bridge_width 0.5)
				(island_removal_mode 0)
			)
			(polygon
				(pts
					(xy 119.6848 -23.5458) (xy 119.6848 -22.9362) (xy 119.8372 -22.9362) (xy 119.8372 -23.5458)
				)
			)
		)
	)
	(footprint ""
		(layer "B.Cu")
		(at 116.205 -61.976 -90)
		(property "Reference" "R223"
			(at -3.429 -0.08763 270)
			(unlocked yes)
			(layer "B.SilkS")
			(effects
				(font
					(size 0.7874 0.5842)
					(thickness 0.1524)
				)
				(justify mirror)
			)
		)
		(property "Value" "VAL*"
			(at -0.02032 2.13233 270)
			(unlocked yes)
			(layer "B.Fab")
			(hide yes)
			(effects
				(font
					(size 0.7874 0.5842)
					(thickness 0.1524)
				)
				(justify mirror)
			)
		)
		(property "Device Type" "RESISTOR-G155-11001-01,1KOHM,1%"
			(at -0.008382 1.210564 270)
			(unlocked yes)
			(layer "B.Fab")
			(hide yes)
			(effects
				(font
					(size 0.7874 0.5842)
					(thickness 0.1524)
				)
				(justify mirror)
			)
		)
		(property "User Part Number" "PARTNUM*"
			(at -0.02032 4.024884 270)
			(unlocked yes)
			(layer "Cmts.User")
			(hide yes)
			(effects
				(font
					(size 0.7874 0.5842)
					(thickness 0.1524)
				)
				(justify mirror)
			)
		)
		(property "Tolerance" "TOL*"
			(at -0.044704 3.05435 270)
			(unlocked yes)
			(layer "Cmts.User")
			(hide yes)
			(effects
				(font
					(size 0.7874 0.5842)
					(thickness 0.1524)
				)
				(justify mirror)
			)
		)
		(duplicate_pad_numbers_are_jumpers no)
		(fp_line
			(start -1.143 0.5588)
			(end -1.143 -0.5588)
			(stroke
				(width 0.1)
				(type default)
			)
			(layer "B.SilkS")
		)
		(fp_line
			(start 1.143 0.5588)
			(end -1.143 0.5588)
			(stroke
				(width 0.1)
				(type default)
			)
			(layer "B.SilkS")
		)
		(fp_line
			(start -1.143 -0.5588)
			(end 1.143 -0.5588)
			(stroke
				(width 0.1)
				(type default)
			)
			(layer "B.SilkS")
		)
		(fp_line
			(start 1.143 -0.5588)
			(end 1.143 0.5588)
			(stroke
				(width 0.1)
				(type default)
			)
			(layer "B.SilkS")
		)
		(fp_rect
			(start 1.143 -0.5588)
			(end -1.143 0.5588)
			(stroke
				(width 0)
				(type default)
			)
			(fill no)
			(layer "B.CrtYd")
		)
		(fp_line
			(start -0.508 0.3048)
			(end -0.508 -0.3048)
			(stroke
				(width 0.1)
				(type default)
			)
			(layer "B.Fab")
		)
		(fp_line
			(start 0.508 0.3048)
			(end -0.508 0.3048)
			(stroke
				(width 0.1)
				(type default)
			)
			(layer "B.Fab")
		)
		(fp_line
			(start -0.508 -0.3048)
			(end 0.508 -0.3048)
			(stroke
				(width 0.1)
				(type default)
			)
			(layer "B.Fab")
		)
		(fp_line
			(start 0.508 -0.3048)
			(end 0.508 0.3048)
			(stroke
				(width 0.1)
				(type default)
			)
			(layer "B.Fab")
		)
		(pad "1" smd rect
			(at 0.5334 0 90)
			(size 0.7112 0.6096)
			(layers "B.Cu" "B.Mask" "B.Paste")
			(net "PUDC")
		)
		(pad "2" smd rect
			(at -0.5334 0 90)
			(size 0.7112 0.6096)
			(layers "B.Cu" "B.Mask" "B.Paste")
			(net "XP3R3V_FPGA")
		)
		(zone
			(layer "B.Cu")
			(hatch none 0.5)
			(connect_pads
				(clearance 0)
			)
			(min_thickness 0.25)
			(keepout
				(tracks allowed)
				(vias not_allowed)
				(pads allowed)
				(copperpour not_allowed)
				(footprints allowed)
			)
			(placement
				(enabled no)
				(sheetname "")
			)
			(fill
				(thermal_gap 0.5)
				(thermal_bridge_width 0.5)
				(island_removal_mode 0)
			)
			(polygon
				(pts
					(xy 116.5098 -61.8998) (xy 116.5098 -62.0522) (xy 115.9002 -62.0522) (xy 115.9002 -61.8998)
				)
			)
		)
	)
	(footprint ""
		(layer "B.Cu")
		(at 18.3134 -21.2852 90)
		(property "Reference" "R45"
			(at -0.0762 -1.08077 270)
			(unlocked yes)
			(layer "B.SilkS")
			(effects
				(font
					(size 0.7874 0.5842)
					(thickness 0.1524)
				)
				(justify mirror)
			)
		)
		(property "Value" "VAL*"
			(at -0.02032 2.13233 90)
			(unlocked yes)
			(layer "B.Fab")
			(hide yes)
			(effects
				(font
					(size 0.7874 0.5842)
					(thickness 0.1524)
				)
				(justify mirror)
			)
		)
		(property "Tolerance" "TOL*"
			(at -0.044704 3.05435 90)
			(unlocked yes)
			(layer "Cmts.User")
			(hide yes)
			(effects
				(font
					(size 0.7874 0.5842)
					(thickness 0.1524)
				)
				(justify mirror)
			)
		)
		(property "User Part Number" "PARTNUM*"
			(at -0.02032 4.024884 90)
			(unlocked yes)
			(layer "Cmts.User")
			(hide yes)
			(effects
				(font
					(size 0.7874 0.5842)
					(thickness 0.1524)
				)
				(justify mirror)
			)
		)
		(property "Device Type" "RESISTOR-G155-133R0-01,33OHM,1%"
			(at -0.008382 1.210564 90)
			(unlocked yes)
			(layer "B.Fab")
			(hide yes)
			(effects
				(font
					(size 0.7874 0.5842)
					(thickness 0.1524)
				)
				(justify mirror)
			)
		)
		(duplicate_pad_numbers_are_jumpers no)
		(fp_line
			(start 1.143 -0.5588)
			(end 1.143 0.5588)
			(stroke
				(width 0.1)
				(type default)
			)
			(layer "B.SilkS")
		)
		(fp_line
			(start -1.143 -0.5588)
			(end 1.143 -0.5588)
			(stroke
				(width 0.1)
				(type default)
			)
			(layer "B.SilkS")
		)
		(fp_line
			(start 1.143 0.5588)
			(end -1.143 0.5588)
			(stroke
				(width 0.1)
				(type default)
			)
			(layer "B.SilkS")
		)
		(fp_line
			(start -1.143 0.5588)
			(end -1.143 -0.5588)
			(stroke
				(width 0.1)
				(type default)
			)
			(layer "B.SilkS")
		)
		(fp_rect
			(start 1.143 0.5588)
			(end -1.143 -0.5588)
			(stroke
				(width 0)
				(type default)
			)
			(fill no)
			(layer "B.CrtYd")
		)
		(fp_line
			(start 0.508 -0.3048)
			(end 0.508 0.3048)
			(stroke
				(width 0.1)
				(type default)
			)
			(layer "B.Fab")
		)
		(fp_line
			(start -0.508 -0.3048)
			(end 0.508 -0.3048)
			(stroke
				(width 0.1)
				(type default)
			)
			(layer "B.Fab")
		)
		(fp_line
			(start 0.508 0.3048)
			(end -0.508 0.3048)
			(stroke
				(width 0.1)
				(type default)
			)
			(layer "B.Fab")
		)
		(fp_line
			(start -0.508 0.3048)
			(end -0.508 -0.3048)
			(stroke
				(width 0.1)
				(type default)
			)
			(layer "B.Fab")
		)
		(pad "1" smd rect
			(at 0.5334 0 270)
			(size 0.7112 0.6096)
			(layers "B.Cu" "B.Mask" "B.Paste")
			(net "EEPROM_SDA")
		)
		(pad "2" smd rect
			(at -0.5334 0 270)
			(size 0.7112 0.6096)
			(layers "B.Cu" "B.Mask" "B.Paste")
			(net "SEC_EEPROM_SDA")
		)
		(zone
			(layer "B.Cu")
			(hatch none 0.5)
			(connect_pads
				(clearance 0)
			)
			(min_thickness 0.25)
			(keepout
				(tracks allowed)
				(vias not_allowed)
				(pads allowed)
				(copperpour not_allowed)
				(footprints allowed)
			)
			(placement
				(enabled no)
				(sheetname "")
			)
			(fill
				(thermal_gap 0.5)
				(thermal_bridge_width 0.5)
				(island_removal_mode 0)
			)
			(polygon
				(pts
					(xy 18.6182 -21.3614) (xy 18.0086 -21.3614) (xy 18.0086 -21.209) (xy 18.6182 -21.209)
				)
			)
		)
	)
	(footprint ""
		(layer "B.Cu")
		(at 103.347012 -42.82313)
		(property "Reference" "R198"
			(at -41.625012 0.94488 0)
			(unlocked yes)
			(layer "B.SilkS")
			(effects
				(font
					(size 0.635 0.4064)
					(thickness 0.1524)
				)
				(justify mirror)
			)
		)
		(property "Value" "VAL*"
			(at 0 3.718306 0)
			(unlocked yes)
			(layer "B.Fab")
			(hide yes)
			(effects
				(font
					(size 0.7874 0.5842)
					(thickness 0.127)
				)
				(justify mirror)
			)
		)
		(property "Device Type" "RESISTOR-G155-11000-01,100OHM,A"
			(at 0 1.432306 0)
			(unlocked yes)
			(layer "B.Fab")
			(hide yes)
			(effects
				(font
					(size 0.7874 0.5842)
					(thickness 0.127)
				)
				(justify mirror)
			)
		)
		(property "User Part Number" "PARTNUM*"
			(at 0 2.575306 0)
			(unlocked yes)
			(layer "Cmts.User")
			(hide yes)
			(effects
				(font
					(size 0.7874 0.5842)
					(thickness 0.127)
				)
				(justify mirror)
			)
		)
		(property "Tolerance" "TOL*"
			(at 0 4.861306 0)
			(unlocked yes)
			(layer "Cmts.User")
			(hide yes)
			(effects
				(font
					(size 0.7874 0.5842)
					(thickness 0.127)
				)
				(justify mirror)
			)
		)
		(duplicate_pad_numbers_are_jumpers no)
		(fp_line
			(start -0.970026 -0.4699)
			(end -0.970026 0.4699)
			(stroke
				(width 0.1)
				(type default)
			)
			(layer "B.SilkS")
		)
		(fp_line
			(start -0.970026 0.4699)
			(end 0.970026 0.4699)
			(stroke
				(width 0.1)
				(type default)
			)
			(layer "B.SilkS")
		)
		(fp_line
			(start 0.970026 -0.4699)
			(end -0.970026 -0.4699)
			(stroke
				(width 0.1)
				(type default)
			)
			(layer "B.SilkS")
		)
		(fp_line
			(start 0.970026 0.4699)
			(end 0.970026 -0.4699)
			(stroke
				(width 0.1)
				(type default)
			)
			(layer "B.SilkS")
		)
		(fp_poly
			(pts
				(xy 0.970026 0.4699) (xy -0.970026 0.4699) (xy -0.970026 -0.4699) (xy 0.970026 -0.4699)
			)
			(stroke
				(width 0)
				(type default)
			)
			(fill no)
			(layer "B.CrtYd")
		)
		(fp_line
			(start -0.508 -0.3048)
			(end -0.508 0.3048)
			(stroke
				(width 0.1)
				(type default)
			)
			(layer "B.Fab")
		)
		(fp_line
			(start -0.508 0.3048)
			(end 0.508 0.3048)
			(stroke
				(width 0.1)
				(type default)
			)
			(layer "B.Fab")
		)
		(fp_line
			(start 0.508 -0.3048)
			(end -0.508 -0.3048)
			(stroke
				(width 0.1)
				(type default)
			)
			(layer "B.Fab")
		)
		(fp_line
			(start 0.508 0.3048)
			(end 0.508 -0.3048)
			(stroke
				(width 0.1)
				(type default)
			)
			(layer "B.Fab")
		)
		(pad "1" smd circle
			(at 0.500126 0 180)
			(size 0.635 0.635)
			(layers "B.Cu" "B.Mask" "B.Paste")
			(net "PCIE_REFCLKP")
		)
		(pad "2" smd circle
			(at -0.500126 0 180)
			(size 0.635 0.635)
			(layers "B.Cu" "B.Mask" "B.Paste")
			(net "PCIE_REFCLKN")
		)
	)
)
